# T6G (Grand Teton) — schematic netlist excerpt (pin names and nets, part order shuffled) for the footprints in the layout excerpt that follows; sources: Cadence DE-HDL packaged netlist, KiCad conversion of 04192023_DAF0TMB3IC0_F0TG_MB_C_brd_V02_OCP.brd

PC1866  Q_CAPP  560UF 6.3V 20% OSCON  pkg THLF  page 190 : A = P3V3_AUX ; B = GND
R1128  Q_RES  1K 1% CHIP  pkg 0402LF  page 136 : A = P3V3_AUX ; B = HP_LVC3_OCP_SFF_PRSNT2
R710  Q_RES  1K 1% CHIP  pkg 0402LF  page 238 : A = PD_MB_FRU_WP ; B = GND

(kicad_pcb
	(version 20260206)
	(generator "pcbnew")
	(generator_version "10.0")
	(general
		(thickness 1.6)
		(legacy_teardrops no)
	)
	(paper "A4")
	(title_block
		(title "04192023_DAF0TMB3IC0_F0TG_MB_C_brd_V02_OCP.brd")
		(comment 1 "Grand Teton / footprints 1035-1037 of 8354")
	)
	(layers
		(0 "F.Cu" signal "TOP")
		(4 "In1.Cu" signal "GND")
		(6 "In2.Cu" signal "IN1")
		(8 "In3.Cu" signal "GND1")
		(10 "In4.Cu" signal "IN2")
		(12 "In5.Cu" signal "GND2")
		(14 "In6.Cu" signal "IN3")
		(16 "In7.Cu" signal "GND3")
		(18 "In8.Cu" signal "VCC")
		(20 "In9.Cu" signal "VCC1")
		(22 "In10.Cu" signal "GND4")
		(24 "In11.Cu" signal "IN4")
		(26 "In12.Cu" signal "GND5")
		(28 "In13.Cu" signal "IN5")
		(30 "In14.Cu" signal "GND6")
		(32 "In15.Cu" signal "IN6")
		(34 "In16.Cu" signal "GND7")
		(2 "B.Cu" signal "BOTTOM")
		(9 "F.Adhes" user "F.Adhesive")
		(11 "B.Adhes" user "B.Adhesive")
		(13 "F.Paste" user "Package Geometry/Pastemask Top")
		(15 "B.Paste" user "Package Geometry/Pastemask Bottom")
		(5 "F.SilkS" user "Ref Des/Silkscreen Top")
		(7 "B.SilkS" user "Ref Des/Silkscreen Bottom")
		(1 "F.Mask" user "Board Geometry/Soldermask Top")
		(3 "B.Mask" user "Board Geometry/Soldermask Bottom")
		(17 "Dwgs.User" user "User.Drawings")
		(19 "Cmts.User" user "User.Comments")
		(21 "Eco1.User" user "User.Eco1")
		(23 "Eco2.User" user "User.Eco2")
		(25 "Edge.Cuts" user "Board Geometry/Outline")
		(27 "Margin" user)
		(31 "F.CrtYd" user "Package Geometry/Place Bound Top")
		(29 "B.CrtYd" user "Package Geometry/Place Bound Bottom")
		(35 "F.Fab" user "Ref Des/Assembly Top")
		(33 "B.Fab" user "Ref Des/Assembly Bottom")
	)
	(footprint ""
		(layer "F.Cu")
		(at 457.200508 -72.373236 180)
		(property "Reference" "PC1866"
			(at -2.201164 -2.058162 0)
			(unlocked yes)
			(layer "F.SilkS")
			(effects
				(font
					(size 0.7874 0.5842)
					(thickness 0.1524)
				)
				(justify left)
			)
		)
		(property "Value" ""
			(at 0 0 180)
			(layer "F.Fab")
			(effects
				(font
					(size 1.27 1.27)
				)
			)
		)
		(duplicate_pad_numbers_are_jumpers no)
		(fp_line
			(start -3.400044 1.249934)
			(end 3.400044 1.249934)
			(stroke
				(width 0.1524)
				(type default)
			)
			(layer "F.SilkS")
		)
		(fp_circle
			(center 0 1.249934)
			(end -3.400044 1.249934)
			(stroke
				(width 0.1524)
				(type default)
			)
			(fill no)
			(layer "F.SilkS")
		)
		(fp_poly
			(pts
				(arc
					(start 3.400044 1.249934)
					(mid 0 4.649978)
					(end -3.400044 1.249934)
				)
			)
			(stroke
				(width 0)
				(type default)
			)
			(fill yes)
			(layer "F.SilkS")
		)
		(fp_circle
			(center 0 1.249934)
			(end -3.400044 1.249934)
			(stroke
				(width 0.1)
				(type default)
			)
			(fill no)
			(layer "F.Fab")
		)
		(pad "1" thru_hole rect
			(at 0 0 180)
			(size 1.524 1.524)
			(drill 1.016)
			(layers "*.Cu" "*.Mask")
			(remove_unused_layers no)
			(net "P3V3_AUX")
			(clearance 0)
			(padstack
				(mode front_inner_back)
				(layer "Inner"
					(shape circle)
					(size 1.524 1.524)
					(clearance 0)
				)
				(layer "B.Cu"
					(shape rect)
					(size 1.524 1.524)
					(clearance 0)
				)
			)
		)
		(pad "2" thru_hole circle
			(at 0 2.500122 180)
			(size 1.524 1.524)
			(drill 1.016)
			(layers "*.Cu" "*.Mask")
			(remove_unused_layers no)
			(net "GND")
			(clearance 0)
		)
	)
	(footprint ""
		(layer "F.Cu")
		(at 319.137538 -117.950488)
		(property "Reference" "R710"
			(at 0 0 0)
			(layer "F.SilkS")
			(hide yes)
			(effects
				(font
					(size 1.27 1.27)
				)
			)
		)
		(property "Value" ""
			(at 0 0 0)
			(layer "F.Fab")
			(effects
				(font
					(size 1.27 1.27)
				)
			)
		)
		(duplicate_pad_numbers_are_jumpers no)
		(fp_line
			(start -0.7874 -0.4064)
			(end 0.7874 -0.4064)
			(stroke
				(width 0.1524)
				(type default)
			)
			(layer "F.SilkS")
		)
		(fp_line
			(start -0.7874 0.4064)
			(end -0.7874 -0.4064)
			(stroke
				(width 0.1524)
				(type default)
			)
			(layer "F.SilkS")
		)
		(fp_line
			(start 0.7874 -0.4064)
			(end 0.7874 0.4064)
			(stroke
				(width 0.1524)
				(type default)
			)
			(layer "F.SilkS")
		)
		(fp_line
			(start 0.7874 0.4064)
			(end -0.7874 0.4064)
			(stroke
				(width 0.1524)
				(type default)
			)
			(layer "F.SilkS")
		)
		(fp_line
			(start -0.67945 -0.305054)
			(end -0.12065 -0.305054)
			(stroke
				(width 0.1)
				(type default)
			)
			(layer "F.Fab")
		)
		(fp_line
			(start -0.67945 0.3048)
			(end -0.67945 -0.305054)
			(stroke
				(width 0.1)
				(type default)
			)
			(layer "F.Fab")
		)
		(fp_line
			(start -0.12065 -0.305054)
			(end -0.12065 -0.2794)
			(stroke
				(width 0.1)
				(type default)
			)
			(layer "F.Fab")
		)
		(fp_line
			(start -0.12065 -0.2794)
			(end 0.12065 -0.2794)
			(stroke
				(width 0.1)
				(type default)
			)
			(layer "F.Fab")
		)
		(fp_line
			(start -0.12065 0.2794)
			(end -0.12065 0.3048)
			(stroke
				(width 0.1)
				(type default)
			)
			(layer "F.Fab")
		)
		(fp_line
			(start -0.12065 0.3048)
			(end -0.67945 0.3048)
			(stroke
				(width 0.1)
				(type default)
			)
			(layer "F.Fab")
		)
		(fp_line
			(start 0.120396 0.2794)
			(end -0.12065 0.2794)
			(stroke
				(width 0.1)
				(type default)
			)
			(layer "F.Fab")
		)
		(fp_line
			(start 0.120396 0.3048)
			(end 0.120396 0.2794)
			(stroke
				(width 0.1)
				(type default)
			)
			(layer "F.Fab")
		)
		(fp_line
			(start 0.12065 -0.3048)
			(end 0.67945 -0.3048)
			(stroke
				(width 0.1)
				(type default)
			)
			(layer "F.Fab")
		)
		(fp_line
			(start 0.12065 -0.2794)
			(end 0.12065 -0.3048)
			(stroke
				(width 0.1)
				(type default)
			)
			(layer "F.Fab")
		)
		(fp_line
			(start 0.67945 -0.3048)
			(end 0.67945 0.3048)
			(stroke
				(width 0.1)
				(type default)
			)
			(layer "F.Fab")
		)
		(fp_line
			(start 0.67945 0.3048)
			(end 0.120396 0.3048)
			(stroke
				(width 0.1)
				(type default)
			)
			(layer "F.Fab")
		)
		(pad "1" smd circle
			(at -0.40005 0)
			(size 0 0)
			(layers "F.Cu" "F.Mask" "F.Paste")
			(net "PD_MB_FRU_WP")
		)
		(pad "2" smd circle
			(at 0.40005 0)
			(size 0 0)
			(layers "F.Cu" "F.Mask" "F.Paste")
			(net "GND")
		)
	)
	(footprint ""
		(layer "F.Cu")
		(at 157.353 -111.887 90)
		(property "Reference" "R1128"
			(at 0 0 90)
			(layer "F.SilkS")
			(hide yes)
			(effects
				(font
					(size 1.27 1.27)
				)
			)
		)
		(property "Value" ""
			(at 0 0 90)
			(layer "F.Fab")
			(effects
				(font
					(size 1.27 1.27)
				)
			)
		)
		(duplicate_pad_numbers_are_jumpers no)
		(fp_line
			(start 0.7874 -0.4064)
			(end 0.7874 0.4064)
			(stroke
				(width 0.1524)
				(type default)
			)
			(layer "F.SilkS")
		)
		(fp_line
			(start -0.7874 -0.4064)
			(end 0.7874 -0.4064)
			(stroke
				(width 0.1524)
				(type default)
			)
			(layer "F.SilkS")
		)
		(fp_line
			(start 0.7874 0.4064)
			(end -0.7874 0.4064)
			(stroke
				(width 0.1524)
				(type default)
			)
			(layer "F.SilkS")
		)
		(fp_line
			(start -0.7874 0.4064)
			(end -0.7874 -0.4064)
			(stroke
				(width 0.1524)
				(type default)
			)
			(layer "F.SilkS")
		)
		(fp_line
			(start -0.12065 -0.305054)
			(end -0.12065 -0.2794)
			(stroke
				(width 0.1)
				(type default)
			)
			(layer "F.Fab")
		)
		(fp_line
			(start -0.67945 -0.305054)
			(end -0.12065 -0.305054)
			(stroke
				(width 0.1)
				(type default)
			)
			(layer "F.Fab")
		)
		(fp_line
			(start 0.67945 -0.3048)
			(end 0.67945 0.3048)
			(stroke
				(width 0.1)
				(type default)
			)
			(layer "F.Fab")
		)
		(fp_line
			(start 0.12065 -0.3048)
			(end 0.67945 -0.3048)
			(stroke
				(width 0.1)
				(type default)
			)
			(layer "F.Fab")
		)
		(fp_line
			(start 0.12065 -0.2794)
			(end 0.12065 -0.3048)
			(stroke
				(width 0.1)
				(type default)
			)
			(layer "F.Fab")
		)
		(fp_line
			(start -0.12065 -0.2794)
			(end 0.12065 -0.2794)
			(stroke
				(width 0.1)
				(type default)
			)
			(layer "F.Fab")
		)
		(fp_line
			(start 0.120396 0.2794)
			(end -0.12065 0.2794)
			(stroke
				(width 0.1)
				(type default)
			)
			(layer "F.Fab")
		)
		(fp_line
			(start -0.12065 0.2794)
			(end -0.12065 0.3048)
			(stroke
				(width 0.1)
				(type default)
			)
			(layer "F.Fab")
		)
		(fp_line
			(start 0.67945 0.3048)
			(end 0.120396 0.3048)
			(stroke
				(width 0.1)
				(type default)
			)
			(layer "F.Fab")
		)
		(fp_line
			(start 0.120396 0.3048)
			(end 0.120396 0.2794)
			(stroke
				(width 0.1)
				(type default)
			)
			(layer "F.Fab")
		)
		(fp_line
			(start -0.12065 0.3048)
			(end -0.67945 0.3048)
			(stroke
				(width 0.1)
				(type default)
			)
			(layer "F.Fab")
		)
		(fp_line
			(start -0.67945 0.3048)
			(end -0.67945 -0.305054)
			(stroke
				(width 0.1)
				(type default)
			)
			(layer "F.Fab")
		)
		(pad "1" smd circle
			(at -0.40005 0 90)
			(size 0 0)
			(layers "F.Cu" "F.Mask" "F.Paste")
			(net "P3V3_AUX")
		)
		(pad "2" smd circle
			(at 0.40005 0 90)
			(size 0 0)
			(layers "F.Cu" "F.Mask" "F.Paste")
			(net "HP_LVC3_OCP_SFF_PRSNT2")
		)
	)
)
